# T6G (Grand Teton) — schematic netlist excerpt (pin names and nets, part order shuffled) for the footprints in the layout excerpt that follows; sources: Cadence DE-HDL packaged netlist, KiCad conversion of 04192023_DAF0TMB3IC0_F0TG_MB_C_brd_V02_OCP.brd

R270  Q_RES  33 5% CHIP  pkg 0402LF  page 82 : A = FM_CPU1_PROCHOT_R_N ; B = CPU1_PROCHOT_N
R3586  Q_RES  33.2 1% CHIP  pkg 0402LF  page 251 : A = SMB_INA230_3V3AUX_SCL ; B = SMB_INA230_1_3V3AUX_SCL_R

(kicad_pcb
	(version 20260206)
	(generator "pcbnew")
	(generator_version "10.0")
	(general
		(thickness 1.6)
		(legacy_teardrops no)
	)
	(paper "A4")
	(title_block
		(title "04192023_DAF0TMB3IC0_F0TG_MB_C_brd_V02_OCP.brd")
		(comment 1 "Grand Teton / footprints 7-8 of 8354")
	)
	(layers
		(0 "F.Cu" signal "TOP")
		(4 "In1.Cu" signal "GND")
		(6 "In2.Cu" signal "IN1")
		(8 "In3.Cu" signal "GND1")
		(10 "In4.Cu" signal "IN2")
		(12 "In5.Cu" signal "GND2")
		(14 "In6.Cu" signal "IN3")
		(16 "In7.Cu" signal "GND3")
		(18 "In8.Cu" signal "VCC")
		(20 "In9.Cu" signal "VCC1")
		(22 "In10.Cu" signal "GND4")
		(24 "In11.Cu" signal "IN4")
		(26 "In12.Cu" signal "GND5")
		(28 "In13.Cu" signal "IN5")
		(30 "In14.Cu" signal "GND6")
		(32 "In15.Cu" signal "IN6")
		(34 "In16.Cu" signal "GND7")
		(2 "B.Cu" signal "BOTTOM")
		(9 "F.Adhes" user "F.Adhesive")
		(11 "B.Adhes" user "B.Adhesive")
		(13 "F.Paste" user "Package Geometry/Pastemask Top")
		(15 "B.Paste" user "Package Geometry/Pastemask Bottom")
		(5 "F.SilkS" user "Ref Des/Silkscreen Top")
		(7 "B.SilkS" user "Ref Des/Silkscreen Bottom")
		(1 "F.Mask" user "Board Geometry/Soldermask Top")
		(3 "B.Mask" user "Board Geometry/Soldermask Bottom")
		(17 "Dwgs.User" user "User.Drawings")
		(19 "Cmts.User" user "User.Comments")
		(21 "Eco1.User" user "User.Eco1")
		(23 "Eco2.User" user "User.Eco2")
		(25 "Edge.Cuts" user "Board Geometry/Outline")
		(27 "Margin" user)
		(31 "F.CrtYd" user "Package Geometry/Place Bound Top")
		(29 "B.CrtYd" user "Package Geometry/Place Bound Bottom")
		(35 "F.Fab" user "Ref Des/Assembly Top")
		(33 "B.Fab" user "Ref Des/Assembly Bottom")
	)
	(footprint ""
		(layer "F.Cu")
		(at 183.769 -100.294948 -90)
		(property "Reference" "R270"
			(at 0 0 270)
			(layer "F.SilkS")
			(hide yes)
			(effects
				(font
					(size 1.27 1.27)
				)
			)
		)
		(property "Value" ""
			(at 0 0 270)
			(layer "F.Fab")
			(effects
				(font
					(size 1.27 1.27)
				)
			)
		)
		(duplicate_pad_numbers_are_jumpers no)
		(fp_line
			(start -0.7874 0.4064)
			(end -0.7874 -0.4064)
			(stroke
				(width 0.1524)
				(type default)
			)
			(layer "F.SilkS")
		)
		(fp_line
			(start 0.7874 0.4064)
			(end -0.7874 0.4064)
			(stroke
				(width 0.1524)
				(type default)
			)
			(layer "F.SilkS")
		)
		(fp_line
			(start -0.7874 -0.4064)
			(end 0.7874 -0.4064)
			(stroke
				(width 0.1524)
				(type default)
			)
			(layer "F.SilkS")
		)
		(fp_line
			(start 0.7874 -0.4064)
			(end 0.7874 0.4064)
			(stroke
				(width 0.1524)
				(type default)
			)
			(layer "F.SilkS")
		)
		(fp_line
			(start -0.67945 0.3048)
			(end -0.67945 -0.305054)
			(stroke
				(width 0.1)
				(type default)
			)
			(layer "F.Fab")
		)
		(fp_line
			(start -0.12065 0.3048)
			(end -0.67945 0.3048)
			(stroke
				(width 0.1)
				(type default)
			)
			(layer "F.Fab")
		)
		(fp_line
			(start 0.120396 0.3048)
			(end 0.120396 0.2794)
			(stroke
				(width 0.1)
				(type default)
			)
			(layer "F.Fab")
		)
		(fp_line
			(start 0.67945 0.3048)
			(end 0.120396 0.3048)
			(stroke
				(width 0.1)
				(type default)
			)
			(layer "F.Fab")
		)
		(fp_line
			(start -0.12065 0.2794)
			(end -0.12065 0.3048)
			(stroke
				(width 0.1)
				(type default)
			)
			(layer "F.Fab")
		)
		(fp_line
			(start 0.120396 0.2794)
			(end -0.12065 0.2794)
			(stroke
				(width 0.1)
				(type default)
			)
			(layer "F.Fab")
		)
		(fp_line
			(start -0.12065 -0.2794)
			(end 0.12065 -0.2794)
			(stroke
				(width 0.1)
				(type default)
			)
			(layer "F.Fab")
		)
		(fp_line
			(start 0.12065 -0.2794)
			(end 0.12065 -0.3048)
			(stroke
				(width 0.1)
				(type default)
			)
			(layer "F.Fab")
		)
		(fp_line
			(start 0.12065 -0.3048)
			(end 0.67945 -0.3048)
			(stroke
				(width 0.1)
				(type default)
			)
			(layer "F.Fab")
		)
		(fp_line
			(start 0.67945 -0.3048)
			(end 0.67945 0.3048)
			(stroke
				(width 0.1)
				(type default)
			)
			(layer "F.Fab")
		)
		(fp_line
			(start -0.67945 -0.305054)
			(end -0.12065 -0.305054)
			(stroke
				(width 0.1)
				(type default)
			)
			(layer "F.Fab")
		)
		(fp_line
			(start -0.12065 -0.305054)
			(end -0.12065 -0.2794)
			(stroke
				(width 0.1)
				(type default)
			)
			(layer "F.Fab")
		)
		(pad "1" smd circle
			(at -0.40005 0 270)
			(size 0 0)
			(layers "F.Cu" "F.Mask" "F.Paste")
			(net "FM_CPU1_PROCHOT_R_N")
		)
		(pad "2" smd circle
			(at 0.40005 0 270)
			(size 0 0)
			(layers "F.Cu" "F.Mask" "F.Paste")
			(net "CPU1_PROCHOT_N")
		)
	)
	(footprint ""
		(layer "F.Cu")
		(at 299.29836 -119.67591 90)
		(property "Reference" "R3586"
			(at 0 0 90)
			(layer "F.SilkS")
			(hide yes)
			(effects
				(font
					(size 1.27 1.27)
				)
			)
		)
		(property "Value" ""
			(at 0 0 90)
			(layer "F.Fab")
			(effects
				(font
					(size 1.27 1.27)
				)
			)
		)
		(duplicate_pad_numbers_are_jumpers no)
		(fp_line
			(start 0.7874 -0.4064)
			(end 0.7874 0.4064)
			(stroke
				(width 0.1524)
				(type default)
			)
			(layer "F.SilkS")
		)
		(fp_line
			(start -0.7874 -0.4064)
			(end 0.7874 -0.4064)
			(stroke
				(width 0.1524)
				(type default)
			)
			(layer "F.SilkS")
		)
		(fp_line
			(start 0.7874 0.4064)
			(end -0.7874 0.4064)
			(stroke
				(width 0.1524)
				(type default)
			)
			(layer "F.SilkS")
		)
		(fp_line
			(start -0.7874 0.4064)
			(end -0.7874 -0.4064)
			(stroke
				(width 0.1524)
				(type default)
			)
			(layer "F.SilkS")
		)
		(fp_line
			(start -0.12065 -0.305054)
			(end -0.12065 -0.2794)
			(stroke
				(width 0.1)
				(type default)
			)
			(layer "F.Fab")
		)
		(fp_line
			(start -0.67945 -0.305054)
			(end -0.12065 -0.305054)
			(stroke
				(width 0.1)
				(type default)
			)
			(layer "F.Fab")
		)
		(fp_line
			(start 0.67945 -0.3048)
			(end 0.67945 0.3048)
			(stroke
				(width 0.1)
				(type default)
			)
			(layer "F.Fab")
		)
		(fp_line
			(start 0.12065 -0.3048)
			(end 0.67945 -0.3048)
			(stroke
				(width 0.1)
				(type default)
			)
			(layer "F.Fab")
		)
		(fp_line
			(start 0.12065 -0.2794)
			(end 0.12065 -0.3048)
			(stroke
				(width 0.1)
				(type default)
			)
			(layer "F.Fab")
		)
		(fp_line
			(start -0.12065 -0.2794)
			(end 0.12065 -0.2794)
			(stroke
				(width 0.1)
				(type default)
			)
			(layer "F.Fab")
		)
		(fp_line
			(start 0.120396 0.2794)
			(end -0.12065 0.2794)
			(stroke
				(width 0.1)
				(type default)
			)
			(layer "F.Fab")
		)
		(fp_line
			(start -0.12065 0.2794)
			(end -0.12065 0.3048)
			(stroke
				(width 0.1)
				(type default)
			)
			(layer "F.Fab")
		)
		(fp_line
			(start 0.67945 0.3048)
			(end 0.120396 0.3048)
			(stroke
				(width 0.1)
				(type default)
			)
			(layer "F.Fab")
		)
		(fp_line
			(start 0.120396 0.3048)
			(end 0.120396 0.2794)
			(stroke
				(width 0.1)
				(type default)
			)
			(layer "F.Fab")
		)
		(fp_line
			(start -0.12065 0.3048)
			(end -0.67945 0.3048)
			(stroke
				(width 0.1)
				(type default)
			)
			(layer "F.Fab")
		)
		(fp_line
			(start -0.67945 0.3048)
			(end -0.67945 -0.305054)
			(stroke
				(width 0.1)
				(type default)
			)
			(layer "F.Fab")
		)
		(pad "1" smd circle
			(at -0.40005 0 90)
			(size 0 0)
			(layers "F.Cu" "F.Mask" "F.Paste")
			(net "SMB_INA230_3V3AUX_SCL")
		)
		(pad "2" smd circle
			(at 0.40005 0 90)
			(size 0 0)
			(layers "F.Cu" "F.Mask" "F.Paste")
			(net "SMB_INA230_1_3V3AUX_SCL_R")
		)
	)
)
